# T6G (Grand Teton) — schematic netlist excerpt (pin names and nets, part order shuffled) for the footprints in the layout excerpt that follows; sources: Cadence DE-HDL packaged netlist, KiCad conversion of 04192023_DAF0TMB3IC0_F0TG_MB_C_brd_V02_OCP.brd

R1174  Q_RES  33.2 1% CHIP  pkg 0402LF  page 142 : A = RST_PERST_OCP_V3_2_N ; B = RST_PERST_OCP_V3_2_R_N
R1175  Q_RES  33.2 1% CHIP  pkg 0402LF  page 142 : A = OCP_V3_2_AUX_PWR_EN_R2 ; B = OCP_V3_2_AUX_PWR_EN

(kicad_pcb
	(version 20260206)
	(generator "pcbnew")
	(generator_version "10.0")
	(general
		(thickness 1.6)
		(legacy_teardrops no)
	)
	(paper "A4")
	(title_block
		(title "04192023_DAF0TMB3IC0_F0TG_MB_C_brd_V02_OCP.brd")
		(comment 1 "Grand Teton / footprints 2850-2851 of 8354")
	)
	(layers
		(0 "F.Cu" signal "TOP")
		(4 "In1.Cu" signal "GND")
		(6 "In2.Cu" signal "IN1")
		(8 "In3.Cu" signal "GND1")
		(10 "In4.Cu" signal "IN2")
		(12 "In5.Cu" signal "GND2")
		(14 "In6.Cu" signal "IN3")
		(16 "In7.Cu" signal "GND3")
		(18 "In8.Cu" signal "VCC")
		(20 "In9.Cu" signal "VCC1")
		(22 "In10.Cu" signal "GND4")
		(24 "In11.Cu" signal "IN4")
		(26 "In12.Cu" signal "GND5")
		(28 "In13.Cu" signal "IN5")
		(30 "In14.Cu" signal "GND6")
		(32 "In15.Cu" signal "IN6")
		(34 "In16.Cu" signal "GND7")
		(2 "B.Cu" signal "BOTTOM")
		(9 "F.Adhes" user "F.Adhesive")
		(11 "B.Adhes" user "B.Adhesive")
		(13 "F.Paste" user "Package Geometry/Pastemask Top")
		(15 "B.Paste" user "Package Geometry/Pastemask Bottom")
		(5 "F.SilkS" user "Ref Des/Silkscreen Top")
		(7 "B.SilkS" user "Ref Des/Silkscreen Bottom")
		(1 "F.Mask" user "Board Geometry/Soldermask Top")
		(3 "B.Mask" user "Board Geometry/Soldermask Bottom")
		(17 "Dwgs.User" user "User.Drawings")
		(19 "Cmts.User" user "User.Comments")
		(21 "Eco1.User" user "User.Eco1")
		(23 "Eco2.User" user "User.Eco2")
		(25 "Edge.Cuts" user "Board Geometry/Outline")
		(27 "Margin" user)
		(31 "F.CrtYd" user "Package Geometry/Place Bound Top")
		(29 "B.CrtYd" user "Package Geometry/Place Bound Bottom")
		(35 "F.Fab" user "Ref Des/Assembly Top")
		(33 "B.Fab" user "Ref Des/Assembly Bottom")
	)
	(footprint ""
		(layer "F.Cu")
		(at 70.739 -53.594)
		(property "Reference" "R1175"
			(at 0 0 0)
			(layer "F.SilkS")
			(hide yes)
			(effects
				(font
					(size 1.27 1.27)
				)
			)
		)
		(property "Value" ""
			(at 0 0 0)
			(layer "F.Fab")
			(effects
				(font
					(size 1.27 1.27)
				)
			)
		)
		(duplicate_pad_numbers_are_jumpers no)
		(fp_line
			(start -0.7874 -0.4064)
			(end 0.7874 -0.4064)
			(stroke
				(width 0.1524)
				(type default)
			)
			(layer "F.SilkS")
		)
		(fp_line
			(start -0.7874 0.4064)
			(end -0.7874 -0.4064)
			(stroke
				(width 0.1524)
				(type default)
			)
			(layer "F.SilkS")
		)
		(fp_line
			(start 0.7874 -0.4064)
			(end 0.7874 0.4064)
			(stroke
				(width 0.1524)
				(type default)
			)
			(layer "F.SilkS")
		)
		(fp_line
			(start 0.7874 0.4064)
			(end -0.7874 0.4064)
			(stroke
				(width 0.1524)
				(type default)
			)
			(layer "F.SilkS")
		)
		(fp_line
			(start -0.67945 -0.305054)
			(end -0.12065 -0.305054)
			(stroke
				(width 0.1)
				(type default)
			)
			(layer "F.Fab")
		)
		(fp_line
			(start -0.67945 0.3048)
			(end -0.67945 -0.305054)
			(stroke
				(width 0.1)
				(type default)
			)
			(layer "F.Fab")
		)
		(fp_line
			(start -0.12065 -0.305054)
			(end -0.12065 -0.2794)
			(stroke
				(width 0.1)
				(type default)
			)
			(layer "F.Fab")
		)
		(fp_line
			(start -0.12065 -0.2794)
			(end 0.12065 -0.2794)
			(stroke
				(width 0.1)
				(type default)
			)
			(layer "F.Fab")
		)
		(fp_line
			(start -0.12065 0.2794)
			(end -0.12065 0.3048)
			(stroke
				(width 0.1)
				(type default)
			)
			(layer "F.Fab")
		)
		(fp_line
			(start -0.12065 0.3048)
			(end -0.67945 0.3048)
			(stroke
				(width 0.1)
				(type default)
			)
			(layer "F.Fab")
		)
		(fp_line
			(start 0.120396 0.2794)
			(end -0.12065 0.2794)
			(stroke
				(width 0.1)
				(type default)
			)
			(layer "F.Fab")
		)
		(fp_line
			(start 0.120396 0.3048)
			(end 0.120396 0.2794)
			(stroke
				(width 0.1)
				(type default)
			)
			(layer "F.Fab")
		)
		(fp_line
			(start 0.12065 -0.3048)
			(end 0.67945 -0.3048)
			(stroke
				(width 0.1)
				(type default)
			)
			(layer "F.Fab")
		)
		(fp_line
			(start 0.12065 -0.2794)
			(end 0.12065 -0.3048)
			(stroke
				(width 0.1)
				(type default)
			)
			(layer "F.Fab")
		)
		(fp_line
			(start 0.67945 -0.3048)
			(end 0.67945 0.3048)
			(stroke
				(width 0.1)
				(type default)
			)
			(layer "F.Fab")
		)
		(fp_line
			(start 0.67945 0.3048)
			(end 0.120396 0.3048)
			(stroke
				(width 0.1)
				(type default)
			)
			(layer "F.Fab")
		)
		(pad "1" smd circle
			(at -0.40005 0)
			(size 0 0)
			(layers "F.Cu" "F.Mask" "F.Paste")
			(net "OCP_V3_2_AUX_PWR_EN_R2")
		)
		(pad "2" smd circle
			(at 0.40005 0)
			(size 0 0)
			(layers "F.Cu" "F.Mask" "F.Paste")
			(net "OCP_V3_2_AUX_PWR_EN")
		)
	)
	(footprint ""
		(layer "F.Cu")
		(at 74.409046 -62.969394 -90)
		(property "Reference" "R1174"
			(at 0 0 270)
			(layer "F.SilkS")
			(hide yes)
			(effects
				(font
					(size 1.27 1.27)
				)
			)
		)
		(property "Value" ""
			(at 0 0 270)
			(layer "F.Fab")
			(effects
				(font
					(size 1.27 1.27)
				)
			)
		)
		(duplicate_pad_numbers_are_jumpers no)
		(fp_line
			(start -0.7874 0.4064)
			(end -0.7874 -0.4064)
			(stroke
				(width 0.1524)
				(type default)
			)
			(layer "F.SilkS")
		)
		(fp_line
			(start 0.7874 0.4064)
			(end -0.7874 0.4064)
			(stroke
				(width 0.1524)
				(type default)
			)
			(layer "F.SilkS")
		)
		(fp_line
			(start -0.7874 -0.4064)
			(end 0.7874 -0.4064)
			(stroke
				(width 0.1524)
				(type default)
			)
			(layer "F.SilkS")
		)
		(fp_line
			(start 0.7874 -0.4064)
			(end 0.7874 0.4064)
			(stroke
				(width 0.1524)
				(type default)
			)
			(layer "F.SilkS")
		)
		(fp_line
			(start -0.67945 0.3048)
			(end -0.67945 -0.305054)
			(stroke
				(width 0.1)
				(type default)
			)
			(layer "F.Fab")
		)
		(fp_line
			(start -0.12065 0.3048)
			(end -0.67945 0.3048)
			(stroke
				(width 0.1)
				(type default)
			)
			(layer "F.Fab")
		)
		(fp_line
			(start 0.120396 0.3048)
			(end 0.120396 0.2794)
			(stroke
				(width 0.1)
				(type default)
			)
			(layer "F.Fab")
		)
		(fp_line
			(start 0.67945 0.3048)
			(end 0.120396 0.3048)
			(stroke
				(width 0.1)
				(type default)
			)
			(layer "F.Fab")
		)
		(fp_line
			(start -0.12065 0.2794)
			(end -0.12065 0.3048)
			(stroke
				(width 0.1)
				(type default)
			)
			(layer "F.Fab")
		)
		(fp_line
			(start 0.120396 0.2794)
			(end -0.12065 0.2794)
			(stroke
				(width 0.1)
				(type default)
			)
			(layer "F.Fab")
		)
		(fp_line
			(start -0.12065 -0.2794)
			(end 0.12065 -0.2794)
			(stroke
				(width 0.1)
				(type default)
			)
			(layer "F.Fab")
		)
		(fp_line
			(start 0.12065 -0.2794)
			(end 0.12065 -0.3048)
			(stroke
				(width 0.1)
				(type default)
			)
			(layer "F.Fab")
		)
		(fp_line
			(start 0.12065 -0.3048)
			(end 0.67945 -0.3048)
			(stroke
				(width 0.1)
				(type default)
			)
			(layer "F.Fab")
		)
		(fp_line
			(start 0.67945 -0.3048)
			(end 0.67945 0.3048)
			(stroke
				(width 0.1)
				(type default)
			)
			(layer "F.Fab")
		)
		(fp_line
			(start -0.67945 -0.305054)
			(end -0.12065 -0.305054)
			(stroke
				(width 0.1)
				(type default)
			)
			(layer "F.Fab")
		)
		(fp_line
			(start -0.12065 -0.305054)
			(end -0.12065 -0.2794)
			(stroke
				(width 0.1)
				(type default)
			)
			(layer "F.Fab")
		)
		(pad "1" smd circle
			(at -0.40005 0 270)
			(size 0 0)
			(layers "F.Cu" "F.Mask" "F.Paste")
			(net "RST_PERST_OCP_V3_2_N")
		)
		(pad "2" smd circle
			(at 0.40005 0 270)
			(size 0 0)
			(layers "F.Cu" "F.Mask" "F.Paste")
			(net "RST_PERST_OCP_V3_2_R_N")
		)
	)
)
